# T6G (Grand Teton) — schematic netlist excerpt (pin names and nets, part order shuffled) for the footprints in the layout excerpt that follows; sources: Cadence DE-HDL packaged netlist, KiCad conversion of 04192023_DAF0TMB3IC0_F0TG_MB_C_brd_V02_OCP.brd

C1526  Q_CAP_DIFFBUS  DIFF BUS_0.22UF 6.3V 20% X6S  pkg C0201  page 67 : \1\ = P5E_CPU1_P3_TX_C_DN<10> ; \2\ = P5E_CPU1_P3_TX_DN<10>
PR246  Q_RES  0 5% CHIP  pkg 0402LF  page 217 : A = VSENSE_PVDDIO_P1_DP ; B = VSENSE_PVDDIO_P1_VSEN1

U58  74LVC2G07DW7  74LVC2G07DW-7 IC  pkg SOT363_0-65_2X1-25XC  page 140
  \1a\  = OCP_V3_2_PRSNT0_R_N
  GND  = GND
  \2a\  = OCP_V3_2_PRSNT1_R_N
  \2y\  = HP_LVC3_OCP_V3_2_PRSNT2_N_R
  VCC  = P3V3_AUX
  \1y\  = HP_LVC3_OCP_V3_2_PRSNT2_N_R

(kicad_pcb
	(version 20260206)
	(generator "pcbnew")
	(generator_version "10.0")
	(general
		(thickness 1.6)
		(legacy_teardrops no)
	)
	(paper "A4")
	(title_block
		(title "04192023_DAF0TMB3IC0_F0TG_MB_C_brd_V02_OCP.brd")
		(comment 1 "Grand Teton / footprints 2776-2778 of 8354")
	)
	(layers
		(0 "F.Cu" signal "TOP")
		(4 "In1.Cu" signal "GND")
		(6 "In2.Cu" signal "IN1")
		(8 "In3.Cu" signal "GND1")
		(10 "In4.Cu" signal "IN2")
		(12 "In5.Cu" signal "GND2")
		(14 "In6.Cu" signal "IN3")
		(16 "In7.Cu" signal "GND3")
		(18 "In8.Cu" signal "VCC")
		(20 "In9.Cu" signal "VCC1")
		(22 "In10.Cu" signal "GND4")
		(24 "In11.Cu" signal "IN4")
		(26 "In12.Cu" signal "GND5")
		(28 "In13.Cu" signal "IN5")
		(30 "In14.Cu" signal "GND6")
		(32 "In15.Cu" signal "IN6")
		(34 "In16.Cu" signal "GND7")
		(2 "B.Cu" signal "BOTTOM")
		(9 "F.Adhes" user "F.Adhesive")
		(11 "B.Adhes" user "B.Adhesive")
		(13 "F.Paste" user "Package Geometry/Pastemask Top")
		(15 "B.Paste" user "Package Geometry/Pastemask Bottom")
		(5 "F.SilkS" user "Ref Des/Silkscreen Top")
		(7 "B.SilkS" user "Ref Des/Silkscreen Bottom")
		(1 "F.Mask" user "Board Geometry/Soldermask Top")
		(3 "B.Mask" user "Board Geometry/Soldermask Bottom")
		(17 "Dwgs.User" user "User.Drawings")
		(19 "Cmts.User" user "User.Comments")
		(21 "Eco1.User" user "User.Eco1")
		(23 "Eco2.User" user "User.Eco2")
		(25 "Edge.Cuts" user "Board Geometry/Outline")
		(27 "Margin" user)
		(31 "F.CrtYd" user "Package Geometry/Place Bound Top")
		(29 "B.CrtYd" user "Package Geometry/Place Bound Bottom")
		(35 "F.Fab" user "Ref Des/Assembly Top")
		(33 "B.Fab" user "Ref Des/Assembly Bottom")
	)
	(footprint ""
		(layer "F.Cu")
		(at 12.954 -79.0194)
		(property "Reference" "U58"
			(at -1.4732 -1.768348 0)
			(unlocked yes)
			(layer "F.SilkS")
			(effects
				(font
					(size 0.7874 0.5842)
					(thickness 0.1524)
				)
				(justify left)
			)
		)
		(property "Value" ""
			(at 0 0 0)
			(layer "F.Fab")
			(effects
				(font
					(size 1.27 1.27)
				)
			)
		)
		(duplicate_pad_numbers_are_jumpers no)
		(fp_line
			(start -1.38176 -1.100074)
			(end -1.38176 1.100074)
			(stroke
				(width 0.1524)
				(type default)
			)
			(layer "F.SilkS")
		)
		(fp_line
			(start -1.38176 1.100074)
			(end 1.38176 1.100074)
			(stroke
				(width 0.1524)
				(type default)
			)
			(layer "F.SilkS")
		)
		(fp_line
			(start -0.592074 -1.100074)
			(end -1.38176 -1.100074)
			(stroke
				(width 0.1524)
				(type default)
			)
			(layer "F.SilkS")
		)
		(fp_line
			(start 0 -0.508)
			(end -0.592074 -1.100074)
			(stroke
				(width 0.1524)
				(type default)
			)
			(layer "F.SilkS")
		)
		(fp_line
			(start 0.592074 -1.100074)
			(end 0 -0.508)
			(stroke
				(width 0.1524)
				(type default)
			)
			(layer "F.SilkS")
		)
		(fp_line
			(start 1.38176 -1.100074)
			(end 0.592074 -1.100074)
			(stroke
				(width 0.1524)
				(type default)
			)
			(layer "F.SilkS")
		)
		(fp_line
			(start 1.38176 1.100074)
			(end 1.38176 -1.100074)
			(stroke
				(width 0.1524)
				(type default)
			)
			(layer "F.SilkS")
		)
		(fp_poly
			(pts
				(xy -1.896618 -0.424688) (xy -1.896618 -0.865124) (xy -1.455928 -0.644906)
			)
			(stroke
				(width 0)
				(type default)
			)
			(fill yes)
			(layer "F.SilkS")
		)
		(fp_line
			(start -0.674878 -1.100074)
			(end -0.674878 1.100074)
			(stroke
				(width 0.1)
				(type default)
			)
			(layer "F.Fab")
		)
		(fp_line
			(start -0.674878 1.100074)
			(end 0.674878 1.100074)
			(stroke
				(width 0.1)
				(type default)
			)
			(layer "F.Fab")
		)
		(fp_line
			(start 0.674878 -1.100074)
			(end -0.674878 -1.100074)
			(stroke
				(width 0.1)
				(type default)
			)
			(layer "F.Fab")
		)
		(fp_line
			(start 0.674878 1.100074)
			(end 0.674878 -1.100074)
			(stroke
				(width 0.1)
				(type default)
			)
			(layer "F.Fab")
		)
		(fp_poly
			(pts
				(xy -1.9431 -0.870204) (xy -1.50241 -0.649986) (xy -1.9431 -0.429768)
			)
			(stroke
				(width 0)
				(type default)
			)
			(fill yes)
			(layer "F.Fab")
		)
		(pad "1" smd rect
			(at -0.94996 -0.649986 270)
			(size 0.4318 0.6096)
			(layers "F.Cu" "F.Mask" "F.Paste")
			(net "OCP_V3_2_PRSNT0_R_N")
		)
		(pad "2" smd rect
			(at -0.94996 0 270)
			(size 0.4318 0.6096)
			(layers "F.Cu" "F.Mask" "F.Paste")
			(net "GND")
		)
		(pad "3" smd rect
			(at -0.94996 0.649986 270)
			(size 0.4318 0.6096)
			(layers "F.Cu" "F.Mask" "F.Paste")
			(net "OCP_V3_2_PRSNT1_R_N")
		)
		(pad "4" smd rect
			(at 0.94996 0.649986 270)
			(size 0.4318 0.6096)
			(layers "F.Cu" "F.Mask" "F.Paste")
			(net "HP_LVC3_OCP_V3_2_PRSNT2_N_R")
		)
		(pad "5" smd rect
			(at 0.94996 0 270)
			(size 0.4318 0.6096)
			(layers "F.Cu" "F.Mask" "F.Paste")
			(net "P3V3_AUX")
		)
		(pad "6" smd rect
			(at 0.94996 -0.649986 270)
			(size 0.4318 0.6096)
			(layers "F.Cu" "F.Mask" "F.Paste")
			(net "HP_LVC3_OCP_V3_2_PRSNT2_N_R")
		)
	)
	(footprint ""
		(layer "F.Cu")
		(at 37.592 -359.664 90)
		(property "Reference" "PR246"
			(at 0 0 90)
			(layer "F.SilkS")
			(hide yes)
			(effects
				(font
					(size 1.27 1.27)
				)
			)
		)
		(property "Value" ""
			(at 0 0 90)
			(layer "F.Fab")
			(effects
				(font
					(size 1.27 1.27)
				)
			)
		)
		(duplicate_pad_numbers_are_jumpers no)
		(fp_line
			(start 0.7874 -0.4064)
			(end 0.7874 0.4064)
			(stroke
				(width 0.1524)
				(type default)
			)
			(layer "F.SilkS")
		)
		(fp_line
			(start -0.7874 -0.4064)
			(end 0.7874 -0.4064)
			(stroke
				(width 0.1524)
				(type default)
			)
			(layer "F.SilkS")
		)
		(fp_line
			(start 0.7874 0.4064)
			(end -0.7874 0.4064)
			(stroke
				(width 0.1524)
				(type default)
			)
			(layer "F.SilkS")
		)
		(fp_line
			(start -0.7874 0.4064)
			(end -0.7874 -0.4064)
			(stroke
				(width 0.1524)
				(type default)
			)
			(layer "F.SilkS")
		)
		(fp_line
			(start -0.12065 -0.305054)
			(end -0.12065 -0.2794)
			(stroke
				(width 0.1)
				(type default)
			)
			(layer "F.Fab")
		)
		(fp_line
			(start -0.67945 -0.305054)
			(end -0.12065 -0.305054)
			(stroke
				(width 0.1)
				(type default)
			)
			(layer "F.Fab")
		)
		(fp_line
			(start 0.67945 -0.3048)
			(end 0.67945 0.3048)
			(stroke
				(width 0.1)
				(type default)
			)
			(layer "F.Fab")
		)
		(fp_line
			(start 0.12065 -0.3048)
			(end 0.67945 -0.3048)
			(stroke
				(width 0.1)
				(type default)
			)
			(layer "F.Fab")
		)
		(fp_line
			(start 0.12065 -0.2794)
			(end 0.12065 -0.3048)
			(stroke
				(width 0.1)
				(type default)
			)
			(layer "F.Fab")
		)
		(fp_line
			(start -0.12065 -0.2794)
			(end 0.12065 -0.2794)
			(stroke
				(width 0.1)
				(type default)
			)
			(layer "F.Fab")
		)
		(fp_line
			(start 0.120396 0.2794)
			(end -0.12065 0.2794)
			(stroke
				(width 0.1)
				(type default)
			)
			(layer "F.Fab")
		)
		(fp_line
			(start -0.12065 0.2794)
			(end -0.12065 0.3048)
			(stroke
				(width 0.1)
				(type default)
			)
			(layer "F.Fab")
		)
		(fp_line
			(start 0.67945 0.3048)
			(end 0.120396 0.3048)
			(stroke
				(width 0.1)
				(type default)
			)
			(layer "F.Fab")
		)
		(fp_line
			(start 0.120396 0.3048)
			(end 0.120396 0.2794)
			(stroke
				(width 0.1)
				(type default)
			)
			(layer "F.Fab")
		)
		(fp_line
			(start -0.12065 0.3048)
			(end -0.67945 0.3048)
			(stroke
				(width 0.1)
				(type default)
			)
			(layer "F.Fab")
		)
		(fp_line
			(start -0.67945 0.3048)
			(end -0.67945 -0.305054)
			(stroke
				(width 0.1)
				(type default)
			)
			(layer "F.Fab")
		)
		(pad "1" smd circle
			(at -0.40005 0 90)
			(size 0 0)
			(layers "F.Cu" "F.Mask" "F.Paste")
			(net "VSENSE_PVDDIO_P1_DP")
		)
		(pad "2" smd circle
			(at 0.40005 0 90)
			(size 0 0)
			(layers "F.Cu" "F.Mask" "F.Paste")
			(net "VSENSE_PVDDIO_P1_VSEN1")
		)
	)
	(footprint ""
		(layer "F.Cu")
		(at 129.723896 -375.49963 -90)
		(property "Reference" "C1526"
			(at 0 0 270)
			(layer "F.SilkS")
			(hide yes)
			(effects
				(font
					(size 1.27 1.27)
				)
			)
		)
		(property "Value" ""
			(at 0 0 270)
			(layer "F.Fab")
			(effects
				(font
					(size 1.27 1.27)
				)
			)
		)
		(duplicate_pad_numbers_are_jumpers no)
		(fp_line
			(start -0.299974 0.150114)
			(end -0.299974 -0.150114)
			(stroke
				(width 0.1)
				(type default)
			)
			(layer "F.Fab")
		)
		(fp_line
			(start 0.299974 0.150114)
			(end -0.299974 0.150114)
			(stroke
				(width 0.1)
				(type default)
			)
			(layer "F.Fab")
		)
		(fp_line
			(start -0.299974 -0.150114)
			(end 0.299974 -0.150114)
			(stroke
				(width 0.1)
				(type default)
			)
			(layer "F.Fab")
		)
		(fp_line
			(start 0.299974 -0.150114)
			(end 0.299974 0.150114)
			(stroke
				(width 0.1)
				(type default)
			)
			(layer "F.Fab")
		)
		(pad "1" smd rect
			(at -0.2667 0 270)
			(size 0.3048 0.381)
			(layers "F.Cu" "F.Mask" "F.Paste")
			(net "P5E_CPU1_P3_TX_C_DN<10>")
		)
		(pad "2" smd rect
			(at 0.2667 0 270)
			(size 0.3048 0.381)
			(layers "F.Cu" "F.Mask" "F.Paste")
			(net "P5E_CPU1_P3_TX_DN<10>")
		)
	)
)
